(kicad_pcb
	(version 20241229)
	(generator "pcbnew")
	(generator_version "9.0")
	(general
		(thickness 1.6)
		(legacy_teardrops no)
	)
	(paper "A4")
	(title_block
		(title "environment-sensor")
		(comment 1 "footprints 93-99 of 109")
	)
	(layers
		(0 "F.Cu" signal)
		(4 "In1.Cu" signal)
		(6 "In2.Cu" signal)
		(2 "B.Cu" signal)
		(9 "F.Adhes" user "F.Adhesive")
		(11 "B.Adhes" user "B.Adhesive")
		(13 "F.Paste" user)
		(15 "B.Paste" user)
		(5 "F.SilkS" user "F.Silkscreen")
		(7 "B.SilkS" user "B.Silkscreen")
		(1 "F.Mask" user)
		(3 "B.Mask" user)
		(17 "Dwgs.User" user "User.Drawings")
		(19 "Cmts.User" user "User.Comments")
		(21 "Eco1.User" user "User.Eco1")
		(23 "Eco2.User" user "User.Eco2")
		(25 "Edge.Cuts" user)
		(27 "Margin" user)
		(31 "F.CrtYd" user "F.Courtyard")
		(29 "B.CrtYd" user "B.Courtyard")
		(35 "F.Fab" user)
		(33 "B.Fab" user)
	)
	(footprint "antmicro-footprints:SOD-923"
		(layer "F.Cu")
		(at 203.085 130.25 90)
		(property "Reference" "D7"
			(at -1.5 0.065 90)
			(unlocked yes)
			(layer "F.SilkS")
			(effects
				(font
					(size 0.65 0.65)
					(thickness 0.15)
				)
			)
		)
		(property "Value" "ESD9X5.0ST5G"
			(at 0 2.4 90)
			(unlocked yes)
			(layer "F.Fab")
			(effects
				(font
					(size 1 1)
					(thickness 0.15)
				)
			)
		)
		(property "Description" "Unidirectional TVS, 30 kV,  SOD-923, 5 V, 65 pF"
			(at 0 0 90)
			(layer "F.Fab")
			(hide yes)
			(effects
				(font
					(size 1.27 1.27)
					(thickness 0.15)
				)
			)
		)
		(property "Author" "Antmicro"
			(at 333.335 -72.835 0)
			(layer "F.Fab")
			(hide yes)
			(effects
				(font
					(size 1 1)
					(thickness 0.15)
				)
			)
		)
		(property "License" "Apache-2.0"
			(at 333.335 -72.835 0)
			(layer "F.Fab")
			(hide yes)
			(effects
				(font
					(size 1 1)
					(thickness 0.15)
				)
			)
		)
		(property "MPN" "ESD9X5.0ST5G"
			(at 333.335 -72.835 0)
			(layer "F.Fab")
			(hide yes)
			(effects
				(font
					(size 1 1)
					(thickness 0.15)
				)
			)
		)
		(property "Manufacturer" "ON Semiconductor"
			(at 333.335 -72.835 0)
			(layer "F.Fab")
			(hide yes)
			(effects
				(font
					(size 1 1)
					(thickness 0.15)
				)
			)
		)
		(property "Public" "False"
			(at 333.335 -72.835 0)
			(layer "F.Fab")
			(hide yes)
			(effects
				(font
					(size 1 1)
					(thickness 0.15)
				)
			)
		)
		(sheetfile "environment-sensor.kicad_sch")
		(attr smd)
		(fp_line
			(start 0.5 -0.4)
			(end 0.5 -0.3)
			(stroke
				(width 0.15)
				(type solid)
			)
			(layer "F.SilkS")
		)
		(fp_line
			(start -0.16 -0.4)
			(end -0.16 0.4)
			(stroke
				(width 0.15)
				(type solid)
			)
			(layer "F.SilkS")
		)
		(fp_line
			(start -0.5 -0.4)
			(end 0.5 -0.4)
			(stroke
				(width 0.15)
				(type solid)
			)
			(layer "F.SilkS")
		)
		(fp_line
			(start -0.5 -0.3)
			(end -0.5 -0.4)
			(stroke
				(width 0.15)
				(type solid)
			)
			(layer "F.SilkS")
		)
		(fp_line
			(start 0.5 0.4)
			(end 0.5 0.3)
			(stroke
				(width 0.15)
				(type solid)
			)
			(layer "F.SilkS")
		)
		(fp_line
			(start -0.5 0.4)
			(end -0.5 0.3)
			(stroke
				(width 0.15)
				(type solid)
			)
			(layer "F.SilkS")
		)
		(fp_line
			(start -0.5 0.4)
			(end 0.5 0.4)
			(stroke
				(width 0.15)
				(type solid)
			)
			(layer "F.SilkS")
		)
		(fp_rect
			(start -0.68 -0.41)
			(end 0.68 0.41)
			(stroke
				(width 0.05)
				(type solid)
			)
			(fill no)
			(layer "F.CrtYd")
		)
		(fp_line
			(start -0.202 -0.3)
			(end -0.202 0.298)
			(stroke
				(width 0.15)
				(type solid)
			)
			(layer "F.Fab")
		)
		(fp_rect
			(start -0.402 -0.3)
			(end 0.4 0.298)
			(stroke
				(width 0.15)
				(type solid)
			)
			(fill no)
			(layer "F.Fab")
		)
		(fp_text user "${REFERENCE}"
			(at 0 1.1 90)
			(unlocked yes)
			(layer "F.Fab")
			(effects
				(font
					(size 1 1)
					(thickness 0.15)
				)
			)
		)
		(pad "1" smd roundrect
			(at -0.438 0 90)
			(size 0.4 0.325)
			(layers "F.Cu" "F.Mask" "F.Paste")
			(roundrect_rratio 0.25)
			(net 1 "GND")
			(pinfunction "C")
			(pintype "passive")
		)
		(pad "2" smd roundrect
			(at 0.436 0 90)
			(size 0.4 0.325)
			(layers "F.Cu" "F.Mask" "F.Paste")
			(roundrect_rratio 0.25)
			(net 2 "+3V3")
			(pinfunction "A")
			(pintype "passive")
		)
	)
	(footprint "antmicro-footprints:R_0402_1005Metric"
		(layer "F.Cu")
		(at 182.91 131.5 180)
		(descr "Resistor SMD 0402")
		(tags "resistor SMD 0402")
		(property "Reference" "R18"
			(at -3.04 -0.4 0)
			(layer "F.SilkS")
			(effects
				(font
					(size 0.7 0.7)
					(thickness 0.15)
				)
				(justify right bottom)
			)
		)
		(property "Value" "R_1M_0402"
			(at -1.011843 1.772047 0)
			(layer "F.Fab")
			(effects
				(font
					(size 0.7 0.7)
					(thickness 0.15)
				)
				(justify right bottom)
			)
		)
		(property "Description" "SMD Chip Resistor, 1 Mohm, ± 1%, 62.5 mW, 0402 [1005 Metric], Thick Film, General Purpose"
			(at 0 0 180)
			(layer "F.Fab")
			(hide yes)
			(effects
				(font
					(size 1.27 1.27)
					(thickness 0.15)
				)
			)
		)
		(property "Author" "Antmicro"
			(at 365.82 263 0)
			(layer "F.Fab")
			(hide yes)
			(effects
				(font
					(size 1 1)
					(thickness 0.15)
				)
			)
		)
		(property "License" "Apache-2.0"
			(at 365.82 263 0)
			(layer "F.Fab")
			(hide yes)
			(effects
				(font
					(size 1 1)
					(thickness 0.15)
				)
			)
		)
		(property "MPN" "CR0402-FX-1004GLF"
			(at 365.82 263 0)
			(layer "F.Fab")
			(hide yes)
			(effects
				(font
					(size 1 1)
					(thickness 0.15)
				)
			)
		)
		(property "Manufacturer" "Bourns"
			(at 365.82 263 0)
			(layer "F.Fab")
			(hide yes)
			(effects
				(font
					(size 1 1)
					(thickness 0.15)
				)
			)
		)
		(property "Public" "False"
			(at 365.82 263 0)
			(layer "F.Fab")
			(hide yes)
			(effects
				(font
					(size 1 1)
					(thickness 0.15)
				)
			)
		)
		(property "Tolerance" "1%"
			(at 365.82 263 0)
			(layer "F.Fab")
			(hide yes)
			(effects
				(font
					(size 1 1)
					(thickness 0.15)
				)
			)
		)
		(property "Val" "1M"
			(at 365.82 263 0)
			(layer "F.Fab")
			(hide yes)
			(effects
				(font
					(size 1 1)
					(thickness 0.15)
				)
			)
		)
		(sheetfile "environment-sensor.kicad_sch")
		(attr smd exclude_from_pos_files exclude_from_bom dnp)
		(fp_rect
			(start -0.925 -0.47)
			(end 0.925 0.47)
			(stroke
				(width 0.05)
				(type default)
			)
			(fill no)
			(layer "F.CrtYd")
		)
		(fp_rect
			(start -0.5 -0.25)
			(end 0.5 0.25)
			(stroke
				(width 0.15)
				(type solid)
			)
			(fill no)
			(layer "F.Fab")
		)
		(pad "1" smd roundrect
			(at -0.48 0 180)
			(size 0.59 0.64)
			(layers "F.Cu" "F.Mask" "F.Paste")
			(roundrect_rratio 0.25)
			(net 86 "/OSC32_IN")
			(pintype "passive")
		)
		(pad "2" smd roundrect
			(at 0.48 0 180)
			(size 0.59 0.64)
			(layers "F.Cu" "F.Mask" "F.Paste")
			(roundrect_rratio 0.25)
			(net 87 "/OSC32_OUT")
			(pintype "passive")
		)
	)
	(footprint "antmicro-footprints:R_0402_1005Metric"
		(layer "F.Cu")
		(at 177.303 123.697 -90)
		(descr "Resistor SMD 0402")
		(tags "resistor SMD 0402")
		(property "Reference" "R11"
			(at 0.053 -2.647 180)
			(layer "F.SilkS")
			(effects
				(font
					(size 0.7 0.7)
					(thickness 0.15)
				)
				(justify right bottom)
			)
		)
		(property "Value" "R_0R_0402"
			(at -1.011843 1.772047 90)
			(layer "F.Fab")
			(effects
				(font
					(size 0.7 0.7)
					(thickness 0.15)
				)
				(justify right bottom)
			)
		)
		(property "Description" "SMD Chip Resistor, Jumper, 0 ohm, 100 mW, 0402 [1005 Metric], Thick Film, General Purpose"
			(at 0 0 270)
			(layer "F.Fab")
			(hide yes)
			(effects
				(font
					(size 1.27 1.27)
					(thickness 0.15)
				)
			)
		)
		(property "Author" "Antmicro"
			(at 53.606 301 0)
			(layer "F.Fab")
			(hide yes)
			(effects
				(font
					(size 1 1)
					(thickness 0.15)
				)
			)
		)
		(property "Current" "1A"
			(at 53.606 301 0)
			(layer "F.Fab")
			(hide yes)
			(effects
				(font
					(size 1 1)
					(thickness 0.15)
				)
			)
		)
		(property "License" "Apache-2.0"
			(at 53.606 301 0)
			(layer "F.Fab")
			(hide yes)
			(effects
				(font
					(size 1 1)
					(thickness 0.15)
				)
			)
		)
		(property "MPN" "ERJ2GE0R00X"
			(at 53.606 301 0)
			(layer "F.Fab")
			(hide yes)
			(effects
				(font
					(size 1 1)
					(thickness 0.15)
				)
			)
		)
		(property "Manufacturer" "Panasonic"
			(at 53.606 301 0)
			(layer "F.Fab")
			(hide yes)
			(effects
				(font
					(size 1 1)
					(thickness 0.15)
				)
			)
		)
		(property "Public" "False"
			(at 53.606 301 0)
			(layer "F.Fab")
			(hide yes)
			(effects
				(font
					(size 1 1)
					(thickness 0.15)
				)
			)
		)
		(property "Tolerance" ""
			(at 53.606 301 0)
			(layer "F.Fab")
			(hide yes)
			(effects
				(font
					(size 1 1)
					(thickness 0.15)
				)
			)
		)
		(property "Val" "0R"
			(at 53.606 301 0)
			(layer "F.Fab")
			(hide yes)
			(effects
				(font
					(size 1 1)
					(thickness 0.15)
				)
			)
		)
		(sheetfile "environment-sensor.kicad_sch")
		(attr smd exclude_from_pos_files exclude_from_bom dnp)
		(fp_rect
			(start -0.925 -0.47)
			(end 0.925 0.47)
			(stroke
				(width 0.05)
				(type default)
			)
			(fill no)
			(layer "F.CrtYd")
		)
		(fp_rect
			(start -0.5 -0.25)
			(end 0.5 0.25)
			(stroke
				(width 0.15)
				(type solid)
			)
			(fill no)
			(layer "F.Fab")
		)
		(pad "1" smd roundrect
			(at -0.48 0 270)
			(size 0.59 0.64)
			(layers "F.Cu" "F.Mask" "F.Paste")
			(roundrect_rratio 0.25)
			(net 43 "Net-(U1-CBUS0)")
			(pintype "passive")
		)
		(pad "2" smd roundrect
			(at 0.48 0 270)
			(size 0.59 0.64)
			(layers "F.Cu" "F.Mask" "F.Paste")
			(roundrect_rratio 0.25)
			(net 21 "/FTDI_USER_PB")
			(pintype "passive")
		)
	)
	(footprint "antmicro-footprints:TP_SMD_1.5mm"
		(locked yes)
		(layer "F.Cu")
		(at 181 116)
		(property "Reference" "TP6"
			(at -1.471 -1.044 0)
			(layer "F.SilkS")
			(hide yes)
			(effects
				(font
					(size 0.7 0.7)
					(thickness 0.15)
				)
				(justify left bottom)
			)
		)
		(property "Value" "TP_1.5mm_SMD"
			(at 0 1.7 0)
			(layer "F.Fab")
			(effects
				(font
					(size 0.7 0.7)
					(thickness 0.15)
				)
				(justify left bottom)
			)
		)
		(property "Description" "test point, SMT"
			(at 0 0 0)
			(layer "F.Fab")
			(hide yes)
			(effects
				(font
					(size 1.27 1.27)
					(thickness 0.15)
				)
			)
		)
		(property "Author" "Antmicro"
			(at 0 0 0)
			(layer "F.Fab")
			(hide yes)
			(effects
				(font
					(size 1 1)
					(thickness 0.15)
				)
			)
		)
		(property "License" "Apache-2.0"
			(at 0 0 0)
			(layer "F.Fab")
			(hide yes)
			(effects
				(font
					(size 1 1)
					(thickness 0.15)
				)
			)
		)
		(property "MPN" ""
			(at 0 0 0)
			(layer "F.Fab")
			(hide yes)
			(effects
				(font
					(size 1 1)
					(thickness 0.15)
				)
			)
		)
		(property "Manufacturer" ""
			(at 0 0 0)
			(layer "F.Fab")
			(hide yes)
			(effects
				(font
					(size 1 1)
					(thickness 0.15)
				)
			)
		)
		(property "Public" "False"
			(at 0 0 0)
			(layer "F.Fab")
			(hide yes)
			(effects
				(font
					(size 1 1)
					(thickness 0.15)
				)
			)
		)
		(sheetfile "environment-sensor.kicad_sch")
		(attr exclude_from_pos_files)
		(pad "1" smd circle
			(at 0 0 270)
			(size 1.5 1.5)
			(layers "F.Cu" "F.Mask")
			(net 25 "JTDI")
			(pinfunction "1")
			(pintype "passive")
		)
	)
	(footprint "antmicro-footprints:R_0402_1005Metric"
		(layer "F.Cu")
		(at 203.75 115.835 -90)
		(descr "Resistor SMD 0402")
		(tags "resistor SMD 0402")
		(property "Reference" "R36"
			(at 4.465 1.55 0)
			(layer "F.SilkS")
			(effects
				(font
					(size 0.7 0.7)
					(thickness 0.15)
				)
				(justify left bottom)
			)
		)
		(property "Value" "R_100k_0402"
			(at 0 1.4 90)
			(layer "F.Fab")
			(effects
				(font
					(size 0.7 0.7)
					(thickness 0.15)
				)
				(justify right bottom)
			)
		)
		(property "Description" "SMD Chip Resistor, 100 kohm, ± 1%, 62.5 mW, 0402 [1005 Metric], Thick Film, General Purpose"
			(at 0 0 270)
			(layer "F.Fab")
			(hide yes)
			(effects
				(font
					(size 1.27 1.27)
					(thickness 0.15)
				)
			)
		)
		(property "Author" "Antmicro"
			(at 87.915 319.585 0)
			(layer "F.Fab")
			(hide yes)
			(effects
				(font
					(size 1 1)
					(thickness 0.15)
				)
			)
		)
		(property "License" "Apache-2.0"
			(at 87.915 319.585 0)
			(layer "F.Fab")
			(hide yes)
			(effects
				(font
					(size 1 1)
					(thickness 0.15)
				)
			)
		)
		(property "MPN" "CR0402-FX-1003GLF"
			(at 87.915 319.585 0)
			(layer "F.Fab")
			(hide yes)
			(effects
				(font
					(size 1 1)
					(thickness 0.15)
				)
			)
		)
		(property "Manufacturer" "Bourns"
			(at 87.915 319.585 0)
			(layer "F.Fab")
			(hide yes)
			(effects
				(font
					(size 1 1)
					(thickness 0.15)
				)
			)
		)
		(property "Public" "False"
			(at 87.915 319.585 0)
			(layer "F.Fab")
			(hide yes)
			(effects
				(font
					(size 1 1)
					(thickness 0.15)
				)
			)
		)
		(property "Tolerance" "1%"
			(at 87.915 319.585 0)
			(layer "F.Fab")
			(hide yes)
			(effects
				(font
					(size 1 1)
					(thickness 0.15)
				)
			)
		)
		(property "Val" "100k"
			(at 87.915 319.585 0)
			(layer "F.Fab")
			(hide yes)
			(effects
				(font
					(size 1 1)
					(thickness 0.15)
				)
			)
		)
		(sheetfile "environment-sensor.kicad_sch")
		(attr smd)
		(fp_rect
			(start -0.925 -0.47)
			(end 0.925 0.47)
			(stroke
				(width 0.05)
				(type default)
			)
			(fill no)
			(layer "F.CrtYd")
		)
		(fp_rect
			(start -0.5 -0.25)
			(end 0.5 0.25)
			(stroke
				(width 0.15)
				(type solid)
			)
			(fill no)
			(layer "F.Fab")
		)
		(pad "1" smd roundrect
			(at -0.48 0 270)
			(size 0.59 0.64)
			(layers "F.Cu" "F.Mask" "F.Paste")
			(roundrect_rratio 0.25)
			(net 1 "GND")
			(pintype "passive")
		)
		(pad "2" smd roundrect
			(at 0.48 0 270)
			(size 0.59 0.64)
			(layers "F.Cu" "F.Mask" "F.Paste")
			(roundrect_rratio 0.25)
			(net 53 "Net-(U6-SDO)")
			(pintype "passive")
		)
	)
	(footprint "antmicro-footprints:TP_SMD_1.5mm"
		(locked yes)
		(layer "F.Cu")
		(at 193.5 116)
		(property "Reference" "TP2"
			(at -1.612 -1.214 0)
			(layer "F.SilkS")
			(hide yes)
			(effects
				(font
					(size 0.7 0.7)
					(thickness 0.15)
				)
				(justify left bottom)
			)
		)
		(property "Value" "TP_1.5mm_SMD"
			(at 0 1.7 0)
			(layer "F.Fab")
			(effects
				(font
					(size 0.7 0.7)
					(thickness 0.15)
				)
				(justify left bottom)
			)
		)
		(property "Description" "test point, SMT"
			(at 0 0 0)
			(layer "F.Fab")
			(hide yes)
			(effects
				(font
					(size 1.27 1.27)
					(thickness 0.15)
				)
			)
		)
		(property "Author" "Antmicro"
			(at 0 0 0)
			(layer "F.Fab")
			(hide yes)
			(effects
				(font
					(size 1 1)
					(thickness 0.15)
				)
			)
		)
		(property "License" "Apache-2.0"
			(at 0 0 0)
			(layer "F.Fab")
			(hide yes)
			(effects
				(font
					(size 1 1)
					(thickness 0.15)
				)
			)
		)
		(property "MPN" ""
			(at 0 0 0)
			(layer "F.Fab")
			(hide yes)
			(effects
				(font
					(size 1 1)
					(thickness 0.15)
				)
			)
		)
		(property "Manufacturer" ""
			(at 0 0 0)
			(layer "F.Fab")
			(hide yes)
			(effects
				(font
					(size 1 1)
					(thickness 0.15)
				)
			)
		)
		(property "Public" "False"
			(at 0 0 0)
			(layer "F.Fab")
			(hide yes)
			(effects
				(font
					(size 1 1)
					(thickness 0.15)
				)
			)
		)
		(sheetfile "environment-sensor.kicad_sch")
		(attr exclude_from_pos_files)
		(pad "1" smd circle
			(at 0 0 270)
			(size 1.5 1.5)
			(layers "F.Cu" "F.Mask")
			(net 13 "JTRST")
			(pinfunction "1")
			(pintype "passive")
		)
	)
	(footprint "antmicro-footprints:LGA-8_2.5x2.5mm_BME280"
		(layer "F.Cu")
		(at 207.5 116 -90)
		(property "Reference" "U6"
			(at 0 -2.301 90)
			(layer "F.SilkS")
			(effects
				(font
					(size 0.7 0.7)
					(thickness 0.15)
				)
				(justify right bottom)
			)
		)
		(property "Value" "BME280"
			(at 0 2.47 90)
			(layer "F.Fab")
			(effects
				(font
					(size 0.7 0.7)
					(thickness 0.15)
				)
				(justify right bottom)
			)
		)
		(property "Description" "Sensor"
			(at 0 0 270)
			(layer "F.Fab")
			(hide yes)
			(effects
				(font
					(size 1.27 1.27)
					(thickness 0.15)
				)
			)
		)
		(property "Author" "Antmicro"
			(at 91.5 323.5 0)
			(layer "F.Fab")
			(hide yes)
			(effects
				(font
					(size 1 1)
					(thickness 0.15)
				)
			)
		)
		(property "License" "Apache-2.0"
			(at 91.5 323.5 0)
			(layer "F.Fab")
			(hide yes)
			(effects
				(font
					(size 1 1)
					(thickness 0.15)
				)
			)
		)
		(property "MPN" "BME280"
			(at 91.5 323.5 0)
			(layer "F.Fab")
			(hide yes)
			(effects
				(font
					(size 1 1)
					(thickness 0.15)
				)
			)
		)
		(property "Manufacturer" "Bosch"
			(at 91.5 323.5 0)
			(layer "F.Fab")
			(hide yes)
			(effects
				(font
					(size 1 1)
					(thickness 0.15)
				)
			)
		)
		(sheetfile "environment-sensor.kicad_sch")
		(attr smd)
		(fp_line
			(start -1.351 1.35)
			(end -0.85 1.35)
			(stroke
				(width 0.15)
				(type solid)
			)
			(layer "F.SilkS")
		)
		(fp_line
			(start -1.351 1.35)
			(end -1.351 0.848)
			(stroke
				(width 0.15)
				(type solid)
			)
			(layer "F.SilkS")
		)
		(fp_line
			(start 1.35 1.35)
			(end 0.848 1.35)
			(stroke
				(width 0.15)
				(type solid)
			)
			(layer "F.SilkS")
		)
		(fp_line
			(start 1.35 1.35)
			(end 1.35 0.848)
			(stroke
				(width 0.15)
				(type solid)
			)
			(layer "F.SilkS")
		)
		(fp_line
			(start -1.351 -1.351)
			(end -1.351 -0.85)
			(stroke
				(width 0.15)
				(type solid)
			)
			(layer "F.SilkS")
		)
		(fp_line
			(start -1.351 -1.351)
			(end -0.85 -1.351)
			(stroke
				(width 0.15)
				(type solid)
			)
			(layer "F.SilkS")
		)
		(fp_line
			(start 1.35 -1.351)
			(end 1.35 -0.975)
			(stroke
				(width 0.15)
				(type solid)
			)
			(layer "F.SilkS")
		)
		(fp_line
			(start 1.35 -1.351)
			(end 0.973 -1.351)
			(stroke
				(width 0.15)
				(type solid)
			)
			(layer "F.SilkS")
		)
		(fp_circle
			(center -1 -1.6)
			(end -0.95 -1.6)
			(stroke
				(width 0.15)
				(type solid)
			)
			(fill yes)
			(layer "F.SilkS")
		)
		(fp_rect
			(start -1.6 -1.6)
			(end 1.6 1.6)
			(stroke
				(width 0.05)
				(type solid)
			)
			(fill no)
			(layer "F.CrtYd")
		)
		(fp_line
			(start -1.25 1.249)
			(end -1.25 -0.635)
			(stroke
				(width 0.15)
				(type solid)
			)
			(layer "F.Fab")
		)
		(fp_line
			(start 1.249 1.249)
			(end -1.25 1.249)
			(stroke
				(width 0.15)
				(type solid)
			)
			(layer "F.Fab")
		)
		(fp_line
			(start -0.635 -1.25)
			(end -1.25 -0.635)
			(stroke
				(width 0.15)
				(type solid)
			)
			(layer "F.Fab")
		)
		(fp_line
			(start -0.635 -1.25)
			(end 1.249 -1.25)
			(stroke
				(width 0.15)
				(type solid)
			)
			(layer "F.Fab")
		)
		(fp_line
			(start 1.249 -1.25)
			(end 1.249 1.249)
			(stroke
				(width 0.15)
				(type solid)
			)
			(layer "F.Fab")
		)
		(pad "1" smd rect
			(at -0.975 -1.025 270)
			(size 0.35 0.5)
			(layers "F.Cu" "F.Mask" "F.Paste")
			(net 1 "GND")
			(pinfunction "GND")
			(pintype "power_in")
		)
		(pad "2" smd rect
			(at -0.327 -1.025 270)
			(size 0.35 0.5)
			(layers "F.Cu" "F.Mask" "F.Paste")
			(net 2 "+3V3")
			(pinfunction "CSB")
			(pintype "input")
		)
		(pad "3" smd rect
			(at 0.325 -1.025 270)
			(size 0.35 0.5)
			(layers "F.Cu" "F.Mask" "F.Paste")
			(net 9 "I2C_1_SDA")
			(pinfunction "SDI")
			(pintype "bidirectional")
		)
		(pad "4" smd rect
			(at 0.973 -1.025 270)
			(size 0.35 0.5)
			(layers "F.Cu" "F.Mask" "F.Paste")
			(net 8 "I2C_1_SCL")
			(pinfunction "SCK")
			(pintype "input")
		)
		(pad "5" smd rect
			(at 0.973 1.024 270)
			(size 0.35 0.5)
			(layers "F.Cu" "F.Mask" "F.Paste")
			(net 53 "Net-(U6-SDO)")
			(pinfunction "SDO")
			(pintype "bidirectional")
		)
		(pad "6" smd rect
			(at 0.325 1.024 270)
			(size 0.35 0.5)
			(layers "F.Cu" "F.Mask" "F.Paste")
			(net 2 "+3V3")
			(pinfunction "VDDIO")
			(pintype "power_in")
		)
		(pad "7" smd rect
			(at -0.327 1.024 270)
			(size 0.35 0.5)
			(layers "F.Cu" "F.Mask" "F.Paste")
			(net 1 "GND")
			(pinfunction "GND")
			(pintype "passive")
		)
		(pad "8" smd rect
			(at -0.975 1.024 270)
			(size 0.35 0.5)
			(layers "F.Cu" "F.Mask" "F.Paste")
			(net 2 "+3V3")
			(pinfunction "VDD")
			(pintype "power_in")
		)
	)
)
